(kicad_pcb
	(version 20221018)
	(generator pcbnew)
	(general
    (thickness 1.6)
  )
	(paper "A4")
	(title_block
    (title "NUC Computer Cluster Power Breakout HW")
    (date "2023-10-18")
    (rev "1.4.3")
    (company "Antmicro Ltd.")
		(comment 9 "footprints 1-9 of 234")
	)
	(layers
    (0 "F.Cu" mixed)
    (1 "In1.Cu" power)
    (2 "In2.Cu" mixed)
    (31 "B.Cu" power)
    (32 "B.Adhes" user "B.Adhesive")
    (33 "F.Adhes" user "F.Adhesive")
    (34 "B.Paste" user)
    (35 "F.Paste" user)
    (36 "B.SilkS" user "B.Silkscreen")
    (37 "F.SilkS" user "F.Silkscreen")
    (38 "B.Mask" user)
    (39 "F.Mask" user)
    (40 "Dwgs.User" user "User.Drawings")
    (41 "Cmts.User" user "User.Comments")
    (42 "Eco1.User" user "User.Eco1")
    (43 "Eco2.User" user "User.Eco2")
    (44 "Edge.Cuts" user)
    (45 "Margin" user)
    (46 "B.CrtYd" user "B.Courtyard")
    (47 "F.CrtYd" user "F.Courtyard")
    (48 "B.Fab" user)
    (49 "F.Fab" user)
  )
	(footprint "antmicro-footprints:R_0402_1005Metric" (layer "F.Cu")
    (at 167.95 96.5 90)
    (descr "Resistor SMD 0402")
    (tags "resistor SMD 0402")
    (property "Author" "Antmicro")
    (property "Current" "1A")
    (property "DNP" "DNP")
    (property "License" "Apache-2.0")
    (property "MPN" "ERJ2GE0R00X")
    (property "Manufacturer" "Panasonic")
    (property "Sheetfile" "pow-cycl-curr-meas.kicad_sch")
    (property "Sheetname" "Power Cycling & Current Measurement")
    (property "Tolerance" "")
    (property "Val" "0R")
    (property "dnp" "")
    (property "exclude_from_bom" "")
    (property "ki_description" "SMD Chip Resistor, Jumper, 0 ohm, 100 mW, 0402 [1005 Metric], Thick Film, General Purpose")
    (property "ki_keywords" "0402, SMT, RESISTOR, PASSIVE")
    (attr smd exclude_from_bom)
    (fp_text reference "R15" (at 0.85 0.45 90) (layer "F.SilkS")
        (effects (font (size 0.7 0.7) (thickness 0.15)) (justify left bottom))
    )
    (fp_text value "R_0R_0402" (at -1.011843 1.772047 90) (layer "F.Fab")
        (effects (font (size 0.7 0.7) (thickness 0.15)) (justify left bottom))
    )
    (fp_text user "${REFERENCE}" (at -0.95 3.168 90) (layer "F.Fab") hide
        (effects (font (size 0.7 0.7) (thickness 0.15)) (justify left bottom))
    )
    (fp_text user "License: Apache-2.0" (at -0.95 5.169 90) (layer "F.Fab") hide
        (effects (font (size 0.7 0.7) (thickness 0.15)) (justify left bottom))
    )
    (fp_text user "Author: Antmicro" (at -0.95 4.169 90) (layer "F.Fab") hide
        (effects (font (size 0.7 0.7) (thickness 0.15)) (justify left bottom))
    )
    (fp_rect (start -0.925 -0.47) (end 0.925 0.47)
      (stroke (width 0.05) (type default)) (fill none) (layer "F.CrtYd"))
    (fp_rect (start -0.5 -0.25) (end 0.5 0.25)
      (stroke (width 0.15) (type solid)) (fill none) (layer "F.Fab"))
    (pad "1" smd roundrect (at -0.48 0 90) (size 0.59 0.64) (layers "F.Cu" "F.Paste" "F.Mask") (roundrect_rratio 0.25)
      (net 1 "VCC3V3") (pintype "passive"))
    (pad "2" smd roundrect (at 0.48 0 90) (size 0.59 0.64) (layers "F.Cu" "F.Paste" "F.Mask") (roundrect_rratio 0.25)
      (net 106 "Net-(U10-A1)") (pintype "passive"))
  )
	(footprint "antmicro-footprints:R_0402_1005Metric" (layer "F.Cu")
    (at 169.05 96.5 -90)
    (descr "Resistor SMD 0402")
    (tags "resistor SMD 0402")
    (property "Author" "Antmicro")
    (property "Current" "1A")
    (property "License" "Apache-2.0")
    (property "MPN" "ERJ2GE0R00X")
    (property "Manufacturer" "Panasonic")
    (property "Sheetfile" "pow-cycl-curr-meas.kicad_sch")
    (property "Sheetname" "Power Cycling & Current Measurement")
    (property "Tolerance" "")
    (property "Val" "0R")
    (property "ki_description" "SMD Chip Resistor, Jumper, 0 ohm, 100 mW, 0402 [1005 Metric], Thick Film, General Purpose")
    (property "ki_keywords" "0402, SMT, RESISTOR, PASSIVE")
    (attr smd)
    (fp_text reference "R16" (at -0.85 -0.4 -90) (layer "F.SilkS")
        (effects (font (size 0.7 0.7) (thickness 0.15)) (justify left bottom))
    )
    (fp_text value "R_0R_0402" (at -1.011843 1.772047 -90) (layer "F.Fab")
        (effects (font (size 0.7 0.7) (thickness 0.15)) (justify left bottom))
    )
    (fp_text user "Author: Antmicro" (at -0.95 4.169 -90) (layer "F.Fab") hide
        (effects (font (size 0.7 0.7) (thickness 0.15)) (justify left bottom))
    )
    (fp_text user "${REFERENCE}" (at -0.95 3.168 -90) (layer "F.Fab") hide
        (effects (font (size 0.7 0.7) (thickness 0.15)) (justify left bottom))
    )
    (fp_text user "License: Apache-2.0" (at -0.95 5.169 -90) (layer "F.Fab") hide
        (effects (font (size 0.7 0.7) (thickness 0.15)) (justify left bottom))
    )
    (fp_rect (start -0.925 -0.47) (end 0.925 0.47)
      (stroke (width 0.05) (type default)) (fill none) (layer "F.CrtYd"))
    (fp_rect (start -0.5 -0.25) (end 0.5 0.25)
      (stroke (width 0.15) (type solid)) (fill none) (layer "F.Fab"))
    (pad "1" smd roundrect (at -0.48 0 270) (size 0.59 0.64) (layers "F.Cu" "F.Paste" "F.Mask") (roundrect_rratio 0.25)
      (net 106 "Net-(U10-A1)") (pintype "passive"))
    (pad "2" smd roundrect (at 0.48 0 270) (size 0.59 0.64) (layers "F.Cu" "F.Paste" "F.Mask") (roundrect_rratio 0.25)
      (net 4 "GND") (pintype "passive"))
  )
	(footprint "antmicro-footprints:R_0402_1005Metric" (layer "F.Cu")
    (at 146.75 101 90)
    (descr "Resistor SMD 0402")
    (tags "resistor SMD 0402")
    (property "Author" "Antmicro")
    (property "Current" "1A")
    (property "DNP" "DNP")
    (property "License" "Apache-2.0")
    (property "MPN" "ERJ2GE0R00X")
    (property "Manufacturer" "Panasonic")
    (property "Sheetfile" "pow-cycl-curr-meas.kicad_sch")
    (property "Sheetname" "Power Cycling & Current Measurement")
    (property "Tolerance" "")
    (property "Val" "0R")
    (property "dnp" "")
    (property "exclude_from_bom" "")
    (property "ki_description" "SMD Chip Resistor, Jumper, 0 ohm, 100 mW, 0402 [1005 Metric], Thick Film, General Purpose")
    (property "ki_keywords" "0402, SMT, RESISTOR, PASSIVE")
    (attr smd exclude_from_bom)
    (fp_text reference "R32" (at -3.1 0.45 90) (layer "F.SilkS")
        (effects (font (size 0.7 0.7) (thickness 0.15)) (justify left bottom))
    )
    (fp_text value "R_0R_0402" (at -1.011843 1.772047 90) (layer "F.Fab")
        (effects (font (size 0.7 0.7) (thickness 0.15)) (justify left bottom))
    )
    (fp_text user "License: Apache-2.0" (at -0.95 5.169 90) (layer "F.Fab") hide
        (effects (font (size 0.7 0.7) (thickness 0.15)) (justify left bottom))
    )
    (fp_text user "${REFERENCE}" (at -0.95 3.168 90) (layer "F.Fab") hide
        (effects (font (size 0.7 0.7) (thickness 0.15)) (justify left bottom))
    )
    (fp_text user "Author: Antmicro" (at -0.95 4.169 90) (layer "F.Fab") hide
        (effects (font (size 0.7 0.7) (thickness 0.15)) (justify left bottom))
    )
    (fp_rect (start -0.925 -0.47) (end 0.925 0.47)
      (stroke (width 0.05) (type default)) (fill none) (layer "F.CrtYd"))
    (fp_rect (start -0.5 -0.25) (end 0.5 0.25)
      (stroke (width 0.15) (type solid)) (fill none) (layer "F.Fab"))
    (pad "1" smd roundrect (at -0.48 0 90) (size 0.59 0.64) (layers "F.Cu" "F.Paste" "F.Mask") (roundrect_rratio 0.25)
      (net 1 "VCC3V3") (pintype "passive"))
    (pad "2" smd roundrect (at 0.48 0 90) (size 0.59 0.64) (layers "F.Cu" "F.Paste" "F.Mask") (roundrect_rratio 0.25)
      (net 110 "Net-(U14-A0)") (pintype "passive"))
  )
	(footprint "antmicro-footprints:R_0402_1005Metric" (layer "F.Cu")
    (at 148.75 101 -90)
    (descr "Resistor SMD 0402")
    (tags "resistor SMD 0402")
    (property "Author" "Antmicro")
    (property "Current" "1A")
    (property "License" "Apache-2.0")
    (property "MPN" "ERJ2GE0R00X")
    (property "Manufacturer" "Panasonic")
    (property "Sheetfile" "pow-cycl-curr-meas.kicad_sch")
    (property "Sheetname" "Power Cycling & Current Measurement")
    (property "Tolerance" "")
    (property "Val" "0R")
    (property "ki_description" "SMD Chip Resistor, Jumper, 0 ohm, 100 mW, 0402 [1005 Metric], Thick Film, General Purpose")
    (property "ki_keywords" "0402, SMT, RESISTOR, PASSIVE")
    (attr smd)
    (fp_text reference "R33" (at -0.85 -0.3 -90) (layer "F.SilkS")
        (effects (font (size 0.7 0.7) (thickness 0.15)) (justify left bottom))
    )
    (fp_text value "R_0R_0402" (at -1.011843 1.772047 -90) (layer "F.Fab")
        (effects (font (size 0.7 0.7) (thickness 0.15)) (justify left bottom))
    )
    (fp_text user "License: Apache-2.0" (at -0.95 5.169 -90) (layer "F.Fab") hide
        (effects (font (size 0.7 0.7) (thickness 0.15)) (justify left bottom))
    )
    (fp_text user "Author: Antmicro" (at -0.95 4.169 -90) (layer "F.Fab") hide
        (effects (font (size 0.7 0.7) (thickness 0.15)) (justify left bottom))
    )
    (fp_text user "${REFERENCE}" (at -0.95 3.168 -90) (layer "F.Fab") hide
        (effects (font (size 0.7 0.7) (thickness 0.15)) (justify left bottom))
    )
    (fp_rect (start -0.925 -0.47) (end 0.925 0.47)
      (stroke (width 0.05) (type default)) (fill none) (layer "F.CrtYd"))
    (fp_rect (start -0.5 -0.25) (end 0.5 0.25)
      (stroke (width 0.15) (type solid)) (fill none) (layer "F.Fab"))
    (pad "1" smd roundrect (at -0.48 0 270) (size 0.59 0.64) (layers "F.Cu" "F.Paste" "F.Mask") (roundrect_rratio 0.25)
      (net 110 "Net-(U14-A0)") (pintype "passive"))
    (pad "2" smd roundrect (at 0.48 0 270) (size 0.59 0.64) (layers "F.Cu" "F.Paste" "F.Mask") (roundrect_rratio 0.25)
      (net 4 "GND") (pintype "passive"))
  )
	(footprint "antmicro-footprints:TP_SMD_1mm" (layer "F.Cu")
    (at 100.757932 105.326324 90)
    (property "Author" "Antmicro")
    (property "License" "Apache-2.0")
    (property "MPN" "")
    (property "Manufacturer" "")
    (property "Sheetfile" "ftdi-module.kicad_sch")
    (property "Sheetname" "FTDI")
    (property "exclude_from_bom" "")
    (property "ki_description" "Test point 1mm SMD")
    (property "ki_keywords" "TESTPOINT")
    (attr exclude_from_pos_files exclude_from_bom)
    (fp_text reference "3V3" (at 0.676324 -1.057932 180) (layer "F.SilkS")
        (effects (font (size 0.7 0.7) (thickness 0.15)) (justify left bottom))
    )
    (fp_text value "TP_1mm_SMD" (at 0 1.4 90) (layer "F.Fab")
        (effects (font (size 0.7 0.7) (thickness 0.15)) (justify left bottom))
    )
    (fp_text user "Author: Antmicro" (at -0.5 4 90) (layer "F.Fab") hide
        (effects (font (size 0.7 0.7) (thickness 0.15)) (justify left bottom))
    )
    (fp_text user "License: Apache-2.0" (at -0.5 5.2 90) (layer "F.Fab") hide
        (effects (font (size 0.7 0.7) (thickness 0.15)) (justify left bottom))
    )
    (fp_text user "${REFERENCE}" (at -0.5 2.8 90) (layer "F.Fab") hide
        (effects (font (size 0.7 0.7) (thickness 0.15)) (justify left bottom))
    )
    (fp_circle (center 0 0) (end 0.6 0)
      (stroke (width 0.05) (type default)) (fill none) (layer "F.CrtYd"))
    (pad "1" smd circle (at 0 0 90) (size 1 1) (layers "F.Cu" "F.Mask")
      (net 1 "VCC3V3") (pinfunction "1") (pintype "passive"))
  )
	(footprint "antmicro-footprints:C_0603_1608Metric" (layer "F.Cu")
    (at 98.75 93.7 180)
    (descr "Capacitor SMD 0603")
    (tags "capacitor 0603")
    (property "Author" "Antmicro")
    (property "Dielectric" "")
    (property "License" "Apache-2.0")
    (property "MPN" "C1608X5R1E106M080AC")
    (property "Manufacturer" "TDK")
    (property "Sheetfile" "daughterboard-supply.kicad_sch")
    (property "Sheetname" "daughterboard-supply")
    (property "Val" "10u")
    (property "Voltage" "25V")
    (property "ki_description" "SMD Multilayer Ceramic Capacitor, 10 µF, 25 V, 0603 [1608 Metric], ± 20%, X5R, C")
    (property "ki_keywords" "0603, SMT, CAPACITOR, PASSIVE, CERAMIC, MLCC")
    (attr smd)
    (fp_text reference "C24" (at -1.25 -1.6) (layer "F.SilkS")
        (effects (font (size 0.7 0.7) (thickness 0.15)) (justify right bottom))
    )
    (fp_text value "C_10u_25V_0603" (at -1.42757 1.770288) (layer "F.Fab")
        (effects (font (size 0.7 0.7) (thickness 0.15)) (justify right bottom))
    )
    (fp_text user "${REFERENCE}" (at -1.682 3.895) (layer "F.Fab") hide
        (effects (font (size 0.7 0.7) (thickness 0.15)) (justify right bottom))
    )
    (fp_text user "Author: Antmicro" (at -1.682 4.894) (layer "F.Fab") hide
        (effects (font (size 0.7 0.7) (thickness 0.15)) (justify right bottom))
    )
    (fp_text user "License: Apache-2.0" (at -1.682 5.895) (layer "F.Fab") hide
        (effects (font (size 0.7 0.7) (thickness 0.15)) (justify right bottom))
    )
    (fp_line (start -0.15 -0.4) (end 0.15 -0.4)
      (stroke (width 0.15) (type solid)) (layer "F.SilkS"))
    (fp_line (start -0.15 0.4) (end 0.15 0.4)
      (stroke (width 0.15) (type solid)) (layer "F.SilkS"))
    (fp_rect (start -1.25 -0.65) (end 1.25 0.65)
      (stroke (width 0.05) (type solid)) (fill none) (layer "F.CrtYd"))
    (fp_rect (start -0.8 -0.4) (end 0.8 0.4)
      (stroke (width 0.15) (type solid)) (fill none) (layer "F.Fab"))
    (pad "1" smd roundrect (at -0.7 0 180) (size 0.8 1) (layers "F.Cu" "F.Paste" "F.Mask") (roundrect_rratio 0.2)
      (net 4 "GND") (pintype "passive"))
    (pad "2" smd roundrect (at 0.7 0 180) (size 0.8 1) (layers "F.Cu" "F.Paste" "F.Mask") (roundrect_rratio 0.2)
      (net 11 "VCC12V0") (pintype "passive"))
  )
	(footprint "antmicro-footprints:C_0402_1005Metric" (layer "F.Cu")
    (at 99.75 88.6 180)
    (descr "Capacitor SMD 0402")
    (tags "capacitor SMD 0402")
    (property "Author" "Antmicro")
    (property "Dielectric" "X5R")
    (property "License" "Apache-2.0")
    (property "MPN" "GRM155R61H104KE14D")
    (property "Manufacturer" "Murata")
    (property "Sheetfile" "daughterboard-supply.kicad_sch")
    (property "Sheetname" "daughterboard-supply")
    (property "Val" "100n")
    (property "Voltage" "50V")
    (property "ki_description" "SMD Multilayer Ceramic Capacitor, 0.1 µF, 50 V, 0402 [1005 Metric], ± 10%, X5R, GRM Series")
    (property "ki_keywords" "0402, SMT, CAPACITOR, PASSIVE, CERAMIC, MLCC")
    (attr smd)
    (fp_text reference "C25" (at -3.15 -0.45) (layer "F.SilkS")
        (effects (font (size 0.7 0.7) (thickness 0.15)) (justify right bottom))
    )
    (fp_text value "C_100n_0402" (at -1.022927 2.155213) (layer "F.Fab")
        (effects (font (size 0.7 0.7) (thickness 0.15)) (justify right bottom))
    )
    (fp_text user "License: Apache-2.0" (at -0.939 5.799) (layer "F.Fab") hide
        (effects (font (size 0.7 0.7) (thickness 0.15)) (justify right bottom))
    )
    (fp_text user "${REFERENCE}" (at -0.939 4.599) (layer "F.Fab") hide
        (effects (font (size 0.7 0.7) (thickness 0.15)) (justify right bottom))
    )
    (fp_text user "Author: Antmicro" (at -0.939 3.399) (layer "F.Fab") hide
        (effects (font (size 0.7 0.7) (thickness 0.15)) (justify right bottom))
    )
    (fp_rect (start -0.925 -0.47) (end 0.925 0.47)
      (stroke (width 0.05) (type default)) (fill none) (layer "F.CrtYd"))
    (fp_line (start -0.494 -0.25) (end 0.504 -0.25)
      (stroke (width 0.15) (type solid)) (layer "F.Fab"))
    (fp_line (start -0.494 0.248) (end -0.494 -0.25)
      (stroke (width 0.15) (type solid)) (layer "F.Fab"))
    (fp_line (start 0.504 -0.25) (end 0.504 0.248)
      (stroke (width 0.15) (type solid)) (layer "F.Fab"))
    (fp_line (start 0.504 0.248) (end -0.494 0.248)
      (stroke (width 0.15) (type solid)) (layer "F.Fab"))
    (pad "1" smd roundrect (at -0.48 0 180) (size 0.59 0.64) (layers "F.Cu" "F.Paste" "F.Mask") (roundrect_rratio 0.25)
      (net 12 "Net-(U15-BST)") (pintype "passive"))
    (pad "2" smd roundrect (at 0.48 0 180) (size 0.59 0.64) (layers "F.Cu" "F.Paste" "F.Mask") (roundrect_rratio 0.25)
      (net 13 "Net-(U15-SW)") (pintype "passive"))
  )
	(footprint "antmicro-footprints:C_0603_1608Metric" (layer "F.Cu")
    (at 97.5 88.35 180)
    (descr "Capacitor SMD 0603")
    (tags "capacitor 0603")
    (property "Author" "Antmicro")
    (property "Dielectric" "")
    (property "License" "Apache-2.0")
    (property "MPN" "GRM188R60J226MEA0D")
    (property "Manufacturer" "Murata")
    (property "Sheetfile" "daughterboard-supply.kicad_sch")
    (property "Sheetname" "daughterboard-supply")
    (property "Val" "22u")
    (property "Voltage" "")
    (property "ki_description" "SMD Multilayer Ceramic Capacitor, 22 µF, 6.3 V, 0603 [1608 Metric], ± 20%, X5R, GRM Series")
    (property "ki_keywords" "0603, SMT, CAPACITOR, PASSIVE, CERAMIC, MLCC")
    (attr smd)
    (fp_text reference "C26" (at -4.35 1.15) (layer "F.SilkS")
        (effects (font (size 0.7 0.7) (thickness 0.15)) (justify right bottom))
    )
    (fp_text value "C_22u_0603" (at -1.42757 1.770288) (layer "F.Fab")
        (effects (font (size 0.7 0.7) (thickness 0.15)) (justify right bottom))
    )
    (fp_text user "${REFERENCE}" (at -1.682 3.895) (layer "F.Fab") hide
        (effects (font (size 0.7 0.7) (thickness 0.15)) (justify right bottom))
    )
    (fp_text user "Author: Antmicro" (at -1.682 4.894) (layer "F.Fab") hide
        (effects (font (size 0.7 0.7) (thickness 0.15)) (justify right bottom))
    )
    (fp_text user "License: Apache-2.0" (at -1.682 5.895) (layer "F.Fab") hide
        (effects (font (size 0.7 0.7) (thickness 0.15)) (justify right bottom))
    )
    (fp_line (start -0.15 -0.4) (end 0.15 -0.4)
      (stroke (width 0.15) (type solid)) (layer "F.SilkS"))
    (fp_line (start -0.15 0.4) (end 0.15 0.4)
      (stroke (width 0.15) (type solid)) (layer "F.SilkS"))
    (fp_rect (start -1.25 -0.65) (end 1.25 0.65)
      (stroke (width 0.05) (type solid)) (fill none) (layer "F.CrtYd"))
    (fp_rect (start -0.8 -0.4) (end 0.8 0.4)
      (stroke (width 0.15) (type solid)) (fill none) (layer "F.Fab"))
    (pad "1" smd roundrect (at -0.7 0 180) (size 0.8 1) (layers "F.Cu" "F.Paste" "F.Mask") (roundrect_rratio 0.2)
      (net 4 "GND") (pintype "passive"))
    (pad "2" smd roundrect (at 0.7 0 180) (size 0.8 1) (layers "F.Cu" "F.Paste" "F.Mask") (roundrect_rratio 0.2)
      (net 2 "VCC5V0") (pintype "passive"))
  )
	(footprint "antmicro-footprints:C_0603_1608Metric" (layer "F.Cu")
    (at 97.5 86.85 180)
    (descr "Capacitor SMD 0603")
    (tags "capacitor 0603")
    (property "Author" "Antmicro")
    (property "Dielectric" "")
    (property "License" "Apache-2.0")
    (property "MPN" "GRM188R60J226MEA0D")
    (property "Manufacturer" "Murata")
    (property "Sheetfile" "daughterboard-supply.kicad_sch")
    (property "Sheetname" "daughterboard-supply")
    (property "Val" "22u")
    (property "Voltage" "")
    (property "ki_description" "SMD Multilayer Ceramic Capacitor, 22 µF, 6.3 V, 0603 [1608 Metric], ± 20%, X5R, GRM Series")
    (property "ki_keywords" "0603, SMT, CAPACITOR, PASSIVE, CERAMIC, MLCC")
    (attr smd)
    (fp_text reference "C27" (at -1.15 0.9) (layer "F.SilkS")
        (effects (font (size 0.7 0.7) (thickness 0.15)) (justify right bottom))
    )
    (fp_text value "C_22u_0603" (at -1.42757 1.770288) (layer "F.Fab")
        (effects (font (size 0.7 0.7) (thickness 0.15)) (justify right bottom))
    )
    (fp_text user "Author: Antmicro" (at -1.682 4.894) (layer "F.Fab") hide
        (effects (font (size 0.7 0.7) (thickness 0.15)) (justify right bottom))
    )
    (fp_text user "${REFERENCE}" (at -1.682 3.895) (layer "F.Fab") hide
        (effects (font (size 0.7 0.7) (thickness 0.15)) (justify right bottom))
    )
    (fp_text user "License: Apache-2.0" (at -1.682 5.895) (layer "F.Fab") hide
        (effects (font (size 0.7 0.7) (thickness 0.15)) (justify right bottom))
    )
    (fp_line (start -0.15 -0.4) (end 0.15 -0.4)
      (stroke (width 0.15) (type solid)) (layer "F.SilkS"))
    (fp_line (start -0.15 0.4) (end 0.15 0.4)
      (stroke (width 0.15) (type solid)) (layer "F.SilkS"))
    (fp_rect (start -1.25 -0.65) (end 1.25 0.65)
      (stroke (width 0.05) (type solid)) (fill none) (layer "F.CrtYd"))
    (fp_rect (start -0.8 -0.4) (end 0.8 0.4)
      (stroke (width 0.15) (type solid)) (fill none) (layer "F.Fab"))
    (pad "1" smd roundrect (at -0.7 0 180) (size 0.8 1) (layers "F.Cu" "F.Paste" "F.Mask") (roundrect_rratio 0.2)
      (net 4 "GND") (pintype "passive"))
    (pad "2" smd roundrect (at 0.7 0 180) (size 0.8 1) (layers "F.Cu" "F.Paste" "F.Mask") (roundrect_rratio 0.2)
      (net 2 "VCC5V0") (pintype "passive"))
  )
)
